(kicad_pcb
	(version 20260206)
	(generator "pcbnew")
	(generator_version "10.0")
	(general
		(thickness 1.6)
		(legacy_teardrops no)
	)
	(paper "A4")
	(title_block
		(title "03242023_DA0F0TMBIJ0_F0T_Motherboard_J_brd_V01_OCP.brd")
		(comment 1 "Grand Teton / footprints 1833-1838 of 6105")
	)
	(layers
		(0 "F.Cu" signal "TOP")
		(4 "In1.Cu" signal "GND")
		(6 "In2.Cu" signal "IN1")
		(8 "In3.Cu" signal "GND1")
		(10 "In4.Cu" signal "IN2")
		(12 "In5.Cu" signal "GND2")
		(14 "In6.Cu" signal "IN3")
		(16 "In7.Cu" signal "GND3")
		(18 "In8.Cu" signal "VCC")
		(20 "In9.Cu" signal "VCC1")
		(22 "In10.Cu" signal "GND4")
		(24 "In11.Cu" signal "IN4")
		(26 "In12.Cu" signal "GND5")
		(28 "In13.Cu" signal "IN5")
		(30 "In14.Cu" signal "GND6")
		(32 "In15.Cu" signal "IN6")
		(34 "In16.Cu" signal "GND7")
		(2 "B.Cu" signal "BOTTOM")
		(9 "F.Adhes" user "F.Adhesive")
		(11 "B.Adhes" user "B.Adhesive")
		(13 "F.Paste" user "Package Geometry/Pastemask Top")
		(15 "B.Paste" user "Package Geometry/Pastemask Bottom")
		(5 "F.SilkS" user "Ref Des/Silkscreen Top")
		(7 "B.SilkS" user "Ref Des/Silkscreen Bottom")
		(1 "F.Mask" user "Board Geometry/Soldermask Top")
		(3 "B.Mask" user "Board Geometry/Soldermask Bottom")
		(17 "Dwgs.User" user "User.Drawings")
		(19 "Cmts.User" user "User.Comments")
		(21 "Eco1.User" user "User.Eco1")
		(23 "Eco2.User" user "User.Eco2")
		(25 "Edge.Cuts" user "Board Geometry/Outline")
		(27 "Margin" user)
		(31 "F.CrtYd" user "Package Geometry/Place Bound Top")
		(29 "B.CrtYd" user "Package Geometry/Place Bound Bottom")
		(35 "F.Fab" user "Ref Des/Assembly Top")
		(33 "B.Fab" user "Ref Des/Assembly Bottom")
	)
	(footprint ""
		(layer "F.Cu")
		(at 126.770384 -66.856356 90)
		(property "Reference" "R927"
			(at 0 0 90)
			(layer "F.SilkS")
			(hide yes)
			(effects
				(font
					(size 1.27 1.27)
				)
			)
		)
		(property "Value" ""
			(at 0 0 90)
			(layer "F.Fab")
			(effects
				(font
					(size 1.27 1.27)
				)
			)
		)
		(duplicate_pad_numbers_are_jumpers no)
		(fp_line
			(start 0.7874 -0.4064)
			(end 0.7874 0.4064)
			(stroke
				(width 0.1524)
				(type default)
			)
			(layer "F.SilkS")
		)
		(fp_line
			(start -0.7874 -0.4064)
			(end 0.7874 -0.4064)
			(stroke
				(width 0.1524)
				(type default)
			)
			(layer "F.SilkS")
		)
		(fp_line
			(start 0.7874 0.4064)
			(end -0.7874 0.4064)
			(stroke
				(width 0.1524)
				(type default)
			)
			(layer "F.SilkS")
		)
		(fp_line
			(start -0.7874 0.4064)
			(end -0.7874 -0.4064)
			(stroke
				(width 0.1524)
				(type default)
			)
			(layer "F.SilkS")
		)
		(fp_line
			(start -0.12065 -0.305054)
			(end -0.12065 -0.2794)
			(stroke
				(width 0.1)
				(type default)
			)
			(layer "F.Fab")
		)
		(fp_line
			(start -0.67945 -0.305054)
			(end -0.12065 -0.305054)
			(stroke
				(width 0.1)
				(type default)
			)
			(layer "F.Fab")
		)
		(fp_line
			(start 0.67945 -0.3048)
			(end 0.67945 0.3048)
			(stroke
				(width 0.1)
				(type default)
			)
			(layer "F.Fab")
		)
		(fp_line
			(start 0.12065 -0.3048)
			(end 0.67945 -0.3048)
			(stroke
				(width 0.1)
				(type default)
			)
			(layer "F.Fab")
		)
		(fp_line
			(start 0.12065 -0.2794)
			(end 0.12065 -0.3048)
			(stroke
				(width 0.1)
				(type default)
			)
			(layer "F.Fab")
		)
		(fp_line
			(start -0.12065 -0.2794)
			(end 0.12065 -0.2794)
			(stroke
				(width 0.1)
				(type default)
			)
			(layer "F.Fab")
		)
		(fp_line
			(start 0.120396 0.2794)
			(end -0.12065 0.2794)
			(stroke
				(width 0.1)
				(type default)
			)
			(layer "F.Fab")
		)
		(fp_line
			(start -0.12065 0.2794)
			(end -0.12065 0.3048)
			(stroke
				(width 0.1)
				(type default)
			)
			(layer "F.Fab")
		)
		(fp_line
			(start 0.67945 0.3048)
			(end 0.120396 0.3048)
			(stroke
				(width 0.1)
				(type default)
			)
			(layer "F.Fab")
		)
		(fp_line
			(start 0.120396 0.3048)
			(end 0.120396 0.2794)
			(stroke
				(width 0.1)
				(type default)
			)
			(layer "F.Fab")
		)
		(fp_line
			(start -0.12065 0.3048)
			(end -0.67945 0.3048)
			(stroke
				(width 0.1)
				(type default)
			)
			(layer "F.Fab")
		)
		(fp_line
			(start -0.67945 0.3048)
			(end -0.67945 -0.305054)
			(stroke
				(width 0.1)
				(type default)
			)
			(layer "F.Fab")
		)
		(pad "1" smd circle
			(at -0.40005 0 90)
			(size 0 0)
			(layers "F.Cu" "F.Mask" "F.Paste")
			(net "P3V3_AUX")
		)
		(pad "2" smd circle
			(at 0.40005 0 90)
			(size 0 0)
			(layers "F.Cu" "F.Mask" "F.Paste")
			(net "JTAG_BMC_PLD_TDI")
		)
	)
	(footprint ""
		(layer "F.Cu")
		(at 27.628596 -394.358876 180)
		(property "Reference" "R3269"
			(at 0 0 180)
			(layer "F.SilkS")
			(hide yes)
			(effects
				(font
					(size 1.27 1.27)
				)
			)
		)
		(property "Value" ""
			(at 0 0 180)
			(layer "F.Fab")
			(effects
				(font
					(size 1.27 1.27)
				)
			)
		)
		(duplicate_pad_numbers_are_jumpers no)
		(fp_line
			(start 0.7874 0.4064)
			(end -0.7874 0.4064)
			(stroke
				(width 0.1524)
				(type default)
			)
			(layer "F.SilkS")
		)
		(fp_line
			(start 0.7874 -0.4064)
			(end 0.7874 0.4064)
			(stroke
				(width 0.1524)
				(type default)
			)
			(layer "F.SilkS")
		)
		(fp_line
			(start -0.7874 0.4064)
			(end -0.7874 -0.4064)
			(stroke
				(width 0.1524)
				(type default)
			)
			(layer "F.SilkS")
		)
		(fp_line
			(start -0.7874 -0.4064)
			(end 0.7874 -0.4064)
			(stroke
				(width 0.1524)
				(type default)
			)
			(layer "F.SilkS")
		)
		(fp_line
			(start 0.67945 0.3048)
			(end 0.120396 0.3048)
			(stroke
				(width 0.1)
				(type default)
			)
			(layer "F.Fab")
		)
		(fp_line
			(start 0.67945 -0.3048)
			(end 0.67945 0.3048)
			(stroke
				(width 0.1)
				(type default)
			)
			(layer "F.Fab")
		)
		(fp_line
			(start 0.12065 -0.2794)
			(end 0.12065 -0.3048)
			(stroke
				(width 0.1)
				(type default)
			)
			(layer "F.Fab")
		)
		(fp_line
			(start 0.12065 -0.3048)
			(end 0.67945 -0.3048)
			(stroke
				(width 0.1)
				(type default)
			)
			(layer "F.Fab")
		)
		(fp_line
			(start 0.120396 0.3048)
			(end 0.120396 0.2794)
			(stroke
				(width 0.1)
				(type default)
			)
			(layer "F.Fab")
		)
		(fp_line
			(start 0.120396 0.2794)
			(end -0.12065 0.2794)
			(stroke
				(width 0.1)
				(type default)
			)
			(layer "F.Fab")
		)
		(fp_line
			(start -0.12065 0.3048)
			(end -0.67945 0.3048)
			(stroke
				(width 0.1)
				(type default)
			)
			(layer "F.Fab")
		)
		(fp_line
			(start -0.12065 0.2794)
			(end -0.12065 0.3048)
			(stroke
				(width 0.1)
				(type default)
			)
			(layer "F.Fab")
		)
		(fp_line
			(start -0.12065 -0.2794)
			(end 0.12065 -0.2794)
			(stroke
				(width 0.1)
				(type default)
			)
			(layer "F.Fab")
		)
		(fp_line
			(start -0.12065 -0.305054)
			(end -0.12065 -0.2794)
			(stroke
				(width 0.1)
				(type default)
			)
			(layer "F.Fab")
		)
		(fp_line
			(start -0.67945 0.3048)
			(end -0.67945 -0.305054)
			(stroke
				(width 0.1)
				(type default)
			)
			(layer "F.Fab")
		)
		(fp_line
			(start -0.67945 -0.305054)
			(end -0.12065 -0.305054)
			(stroke
				(width 0.1)
				(type default)
			)
			(layer "F.Fab")
		)
		(pad "1" smd circle
			(at -0.40005 0 180)
			(size 0 0)
			(layers "F.Cu" "F.Mask" "F.Paste")
			(net "P3V3_AUX")
		)
		(pad "2" smd circle
			(at 0.40005 0 180)
			(size 0 0)
			(layers "F.Cu" "F.Mask" "F.Paste")
			(net "FM_P2E_FGB")
		)
	)
	(footprint ""
		(layer "F.Cu")
		(at 448.177412 -30.131258 90)
		(property "Reference" "PC2154"
			(at 0 0 90)
			(layer "F.SilkS")
			(hide yes)
			(effects
				(font
					(size 1.27 1.27)
				)
			)
		)
		(property "Value" ""
			(at 0 0 90)
			(layer "F.Fab")
			(effects
				(font
					(size 1.27 1.27)
				)
			)
		)
		(duplicate_pad_numbers_are_jumpers no)
		(fp_line
			(start 0.7874 -0.4064)
			(end 0.7874 0.4064)
			(stroke
				(width 0.1524)
				(type default)
			)
			(layer "F.SilkS")
		)
		(fp_line
			(start -0.7874 -0.4064)
			(end 0.7874 -0.4064)
			(stroke
				(width 0.1524)
				(type default)
			)
			(layer "F.SilkS")
		)
		(fp_line
			(start 0.7874 0.4064)
			(end -0.7874 0.4064)
			(stroke
				(width 0.1524)
				(type default)
			)
			(layer "F.SilkS")
		)
		(fp_line
			(start -0.7874 0.4064)
			(end -0.7874 -0.4064)
			(stroke
				(width 0.1524)
				(type default)
			)
			(layer "F.SilkS")
		)
		(fp_line
			(start -0.12065 -0.305054)
			(end -0.12065 -0.2794)
			(stroke
				(width 0.1)
				(type default)
			)
			(layer "F.Fab")
		)
		(fp_line
			(start -0.67945 -0.305054)
			(end -0.12065 -0.305054)
			(stroke
				(width 0.1)
				(type default)
			)
			(layer "F.Fab")
		)
		(fp_line
			(start 0.67945 -0.3048)
			(end 0.67945 0.3048)
			(stroke
				(width 0.1)
				(type default)
			)
			(layer "F.Fab")
		)
		(fp_line
			(start 0.12065 -0.3048)
			(end 0.67945 -0.3048)
			(stroke
				(width 0.1)
				(type default)
			)
			(layer "F.Fab")
		)
		(fp_line
			(start 0.12065 -0.2794)
			(end 0.12065 -0.3048)
			(stroke
				(width 0.1)
				(type default)
			)
			(layer "F.Fab")
		)
		(fp_line
			(start -0.12065 -0.2794)
			(end 0.12065 -0.2794)
			(stroke
				(width 0.1)
				(type default)
			)
			(layer "F.Fab")
		)
		(fp_line
			(start 0.120396 0.2794)
			(end -0.12065 0.2794)
			(stroke
				(width 0.1)
				(type default)
			)
			(layer "F.Fab")
		)
		(fp_line
			(start -0.12065 0.2794)
			(end -0.12065 0.3048)
			(stroke
				(width 0.1)
				(type default)
			)
			(layer "F.Fab")
		)
		(fp_line
			(start 0.67945 0.3048)
			(end 0.120396 0.3048)
			(stroke
				(width 0.1)
				(type default)
			)
			(layer "F.Fab")
		)
		(fp_line
			(start 0.120396 0.3048)
			(end 0.120396 0.2794)
			(stroke
				(width 0.1)
				(type default)
			)
			(layer "F.Fab")
		)
		(fp_line
			(start -0.12065 0.3048)
			(end -0.67945 0.3048)
			(stroke
				(width 0.1)
				(type default)
			)
			(layer "F.Fab")
		)
		(fp_line
			(start -0.67945 0.3048)
			(end -0.67945 -0.305054)
			(stroke
				(width 0.1)
				(type default)
			)
			(layer "F.Fab")
		)
		(pad "1" smd circle
			(at -0.40005 0 90)
			(size 0 0)
			(layers "F.Cu" "F.Mask" "F.Paste")
			(net "P12V_AUX")
		)
		(pad "2" smd circle
			(at 0.40005 0 90)
			(size 0 0)
			(layers "F.Cu" "F.Mask" "F.Paste")
			(net "GND")
		)
	)
	(footprint ""
		(layer "F.Cu")
		(at 331.523848 -402.371052 -90)
		(property "Reference" "C1560"
			(at 0 0 270)
			(layer "F.SilkS")
			(hide yes)
			(effects
				(font
					(size 1.27 1.27)
				)
			)
		)
		(property "Value" ""
			(at 0 0 270)
			(layer "F.Fab")
			(effects
				(font
					(size 1.27 1.27)
				)
			)
		)
		(duplicate_pad_numbers_are_jumpers no)
		(fp_line
			(start -0.299974 0.150114)
			(end -0.299974 -0.150114)
			(stroke
				(width 0.1)
				(type default)
			)
			(layer "F.Fab")
		)
		(fp_line
			(start 0.299974 0.150114)
			(end -0.299974 0.150114)
			(stroke
				(width 0.1)
				(type default)
			)
			(layer "F.Fab")
		)
		(fp_line
			(start -0.299974 -0.150114)
			(end 0.299974 -0.150114)
			(stroke
				(width 0.1)
				(type default)
			)
			(layer "F.Fab")
		)
		(fp_line
			(start 0.299974 -0.150114)
			(end 0.299974 0.150114)
			(stroke
				(width 0.1)
				(type default)
			)
			(layer "F.Fab")
		)
		(pad "1" smd rect
			(at -0.2667 0 270)
			(size 0.3048 0.381)
			(layers "F.Cu" "F.Mask" "F.Paste")
			(net "P5E_CPU0_PE4_TX_C_DN<9>")
		)
		(pad "2" smd rect
			(at 0.2667 0 270)
			(size 0.3048 0.381)
			(layers "F.Cu" "F.Mask" "F.Paste")
			(net "P5E_CPU0_PE4_TX_DN<9>")
		)
	)
	(footprint ""
		(layer "F.Cu")
		(at 418.90188 -156.632148 90)
		(property "Reference" "PC175"
			(at 0 0 90)
			(layer "F.SilkS")
			(hide yes)
			(effects
				(font
					(size 1.27 1.27)
				)
			)
		)
		(property "Value" ""
			(at 0 0 90)
			(layer "F.Fab")
			(effects
				(font
					(size 1.27 1.27)
				)
			)
		)
		(duplicate_pad_numbers_are_jumpers no)
		(fp_line
			(start 0.7874 -0.4064)
			(end 0.7874 0.4064)
			(stroke
				(width 0.1524)
				(type default)
			)
			(layer "F.SilkS")
		)
		(fp_line
			(start -0.7874 -0.4064)
			(end 0.7874 -0.4064)
			(stroke
				(width 0.1524)
				(type default)
			)
			(layer "F.SilkS")
		)
		(fp_line
			(start 0.7874 0.4064)
			(end -0.7874 0.4064)
			(stroke
				(width 0.1524)
				(type default)
			)
			(layer "F.SilkS")
		)
		(fp_line
			(start -0.7874 0.4064)
			(end -0.7874 -0.4064)
			(stroke
				(width 0.1524)
				(type default)
			)
			(layer "F.SilkS")
		)
		(fp_line
			(start -0.12065 -0.305054)
			(end -0.12065 -0.2794)
			(stroke
				(width 0.1)
				(type default)
			)
			(layer "F.Fab")
		)
		(fp_line
			(start -0.67945 -0.305054)
			(end -0.12065 -0.305054)
			(stroke
				(width 0.1)
				(type default)
			)
			(layer "F.Fab")
		)
		(fp_line
			(start 0.67945 -0.3048)
			(end 0.67945 0.3048)
			(stroke
				(width 0.1)
				(type default)
			)
			(layer "F.Fab")
		)
		(fp_line
			(start 0.12065 -0.3048)
			(end 0.67945 -0.3048)
			(stroke
				(width 0.1)
				(type default)
			)
			(layer "F.Fab")
		)
		(fp_line
			(start 0.12065 -0.2794)
			(end 0.12065 -0.3048)
			(stroke
				(width 0.1)
				(type default)
			)
			(layer "F.Fab")
		)
		(fp_line
			(start -0.12065 -0.2794)
			(end 0.12065 -0.2794)
			(stroke
				(width 0.1)
				(type default)
			)
			(layer "F.Fab")
		)
		(fp_line
			(start 0.120396 0.2794)
			(end -0.12065 0.2794)
			(stroke
				(width 0.1)
				(type default)
			)
			(layer "F.Fab")
		)
		(fp_line
			(start -0.12065 0.2794)
			(end -0.12065 0.3048)
			(stroke
				(width 0.1)
				(type default)
			)
			(layer "F.Fab")
		)
		(fp_line
			(start 0.67945 0.3048)
			(end 0.120396 0.3048)
			(stroke
				(width 0.1)
				(type default)
			)
			(layer "F.Fab")
		)
		(fp_line
			(start 0.120396 0.3048)
			(end 0.120396 0.2794)
			(stroke
				(width 0.1)
				(type default)
			)
			(layer "F.Fab")
		)
		(fp_line
			(start -0.12065 0.3048)
			(end -0.67945 0.3048)
			(stroke
				(width 0.1)
				(type default)
			)
			(layer "F.Fab")
		)
		(fp_line
			(start -0.67945 0.3048)
			(end -0.67945 -0.305054)
			(stroke
				(width 0.1)
				(type default)
			)
			(layer "F.Fab")
		)
		(pad "1" smd circle
			(at -0.40005 0 90)
			(size 0 0)
			(layers "F.Cu" "F.Mask" "F.Paste")
			(net "PVCCFA_EHV_CPU0_VDD1")
		)
		(pad "2" smd circle
			(at 0.40005 0 90)
			(size 0 0)
			(layers "F.Cu" "F.Mask" "F.Paste")
			(net "GND")
		)
	)
	(footprint ""
		(layer "F.Cu")
		(at 94.045278 -96.176846)
		(property "Reference" "Q97"
			(at -3.64236 -0.033528 0)
			(unlocked yes)
			(layer "F.SilkS")
			(effects
				(font
					(size 0.7874 0.5842)
					(thickness 0.1524)
				)
			)
		)
		(property "Value" ""
			(at 0 0 0)
			(layer "F.Fab")
			(effects
				(font
					(size 1.27 1.27)
				)
			)
		)
		(duplicate_pad_numbers_are_jumpers no)
		(fp_line
			(start -1.376172 -1.199896)
			(end -0.508 -1.199896)
			(stroke
				(width 0.1524)
				(type default)
			)
			(layer "F.SilkS")
		)
		(fp_line
			(start -1.376172 1.199896)
			(end -1.376172 -1.199896)
			(stroke
				(width 0.1524)
				(type default)
			)
			(layer "F.SilkS")
		)
		(fp_line
			(start -0.508 -1.199896)
			(end 0 -0.762)
			(stroke
				(width 0.1524)
				(type default)
			)
			(layer "F.SilkS")
		)
		(fp_line
			(start 0 -0.762)
			(end 0.508 -1.199896)
			(stroke
				(width 0.1524)
				(type default)
			)
			(layer "F.SilkS")
		)
		(fp_line
			(start 0.508 -1.199896)
			(end 1.376172 -1.199896)
			(stroke
				(width 0.1524)
				(type default)
			)
			(layer "F.SilkS")
		)
		(fp_line
			(start 1.376172 -1.199896)
			(end 1.376172 1.199896)
			(stroke
				(width 0.1524)
				(type default)
			)
			(layer "F.SilkS")
		)
		(fp_line
			(start 1.376172 1.199896)
			(end -1.376172 1.199896)
			(stroke
				(width 0.1524)
				(type default)
			)
			(layer "F.SilkS")
		)
		(fp_poly
			(pts
				(xy -0.9144 -1.302004) (xy -1.2954 -2.064004) (xy -0.5334 -2.064004)
			)
			(stroke
				(width 0)
				(type default)
			)
			(fill yes)
			(layer "F.SilkS")
		)
		(fp_line
			(start -0.674878 -1.100074)
			(end 0.674878 -1.100074)
			(stroke
				(width 0.1)
				(type default)
			)
			(layer "F.Fab")
		)
		(fp_line
			(start -0.674878 1.100074)
			(end -0.674878 -1.100074)
			(stroke
				(width 0.1)
				(type default)
			)
			(layer "F.Fab")
		)
		(fp_line
			(start 0.674878 -1.100074)
			(end 0.674878 1.100074)
			(stroke
				(width 0.1)
				(type default)
			)
			(layer "F.Fab")
		)
		(fp_line
			(start 0.674878 1.100074)
			(end -0.674878 1.100074)
			(stroke
				(width 0.1)
				(type default)
			)
			(layer "F.Fab")
		)
		(fp_poly
			(pts
				(xy -1.4605 -0.7493) (xy -2.2225 -1.1303) (xy -2.2225 -0.3683)
			)
			(stroke
				(width 0)
				(type default)
			)
			(fill yes)
			(layer "F.Fab")
		)
		(pad "1" smd rect
			(at -0.899922 -0.750062 270)
			(size 0.6096 0.6096)
			(layers "F.Cu" "F.Mask" "F.Paste")
			(net "GND")
		)
		(pad "2" smd rect
			(at -0.899922 0 270)
			(size 0.4064 0.6096)
			(layers "F.Cu" "F.Mask" "F.Paste")
			(net "RST_PLD_CPU0_DRAM_EF_N")
		)
		(pad "3" smd rect
			(at -0.899922 0.750062 270)
			(size 0.6096 0.6096)
			(layers "F.Cu" "F.Mask" "F.Paste")
			(net "LED_RST_PLD_CPU0_DRAM_GH_N_D")
		)
		(pad "4" smd rect
			(at 0.899922 0.750062 270)
			(size 0.6096 0.6096)
			(layers "F.Cu" "F.Mask" "F.Paste")
			(net "GND")
		)
		(pad "5" smd rect
			(at 0.899922 0 270)
			(size 0.4064 0.6096)
			(layers "F.Cu" "F.Mask" "F.Paste")
			(net "RST_PLD_CPU0_DRAM_GH_N")
		)
		(pad "6" smd rect
			(at 0.899922 -0.750062 270)
			(size 0.6096 0.6096)
			(layers "F.Cu" "F.Mask" "F.Paste")
			(net "LED_RST_PLD_CPU0_DRAM_EF_N_D")
		)
	)
)
